# S9S_MB_2U (Grand Teton) — schematic netlist excerpt (pin names and nets, part order shuffled) for the footprints in the layout excerpt that follows; sources: Cadence DE-HDL packaged netlist, KiCad conversion of 03242023_DA0F0TMBIJ0_F0T_Motherboard_J_brd_V01_OCP.brd

R4157  Q_RES  33.2 1% CHIP  pkg 0402LF  page 215 : A = PRSNT_CABLE_GPU_A1_ISO_N ; B = PRSNT_CABLE_GPU_A1_ISO_R_N

X3  TP_TDR_4P_FTS  TP_TDR_4P_DIP EMPTY  pkg TH  page 309
  S1  = TDR_DIFF_85_IN2_DP
  P1  = T1_GND
  P2  = T1_GND
  S2  = TDR_DIFF_85_IN2_DN

(kicad_pcb
	(version 20260206)
	(generator "pcbnew")
	(generator_version "10.0")
	(general
		(thickness 1.6)
		(legacy_teardrops no)
	)
	(paper "A4")
	(title_block
		(title "03242023_DA0F0TMBIJ0_F0T_Motherboard_J_brd_V01_OCP.brd")
		(comment 1 "Grand Teton / footprints 3497-3498 of 6105")
	)
	(layers
		(0 "F.Cu" signal "TOP")
		(4 "In1.Cu" signal "GND")
		(6 "In2.Cu" signal "IN1")
		(8 "In3.Cu" signal "GND1")
		(10 "In4.Cu" signal "IN2")
		(12 "In5.Cu" signal "GND2")
		(14 "In6.Cu" signal "IN3")
		(16 "In7.Cu" signal "GND3")
		(18 "In8.Cu" signal "VCC")
		(20 "In9.Cu" signal "VCC1")
		(22 "In10.Cu" signal "GND4")
		(24 "In11.Cu" signal "IN4")
		(26 "In12.Cu" signal "GND5")
		(28 "In13.Cu" signal "IN5")
		(30 "In14.Cu" signal "GND6")
		(32 "In15.Cu" signal "IN6")
		(34 "In16.Cu" signal "GND7")
		(2 "B.Cu" signal "BOTTOM")
		(9 "F.Adhes" user "F.Adhesive")
		(11 "B.Adhes" user "B.Adhesive")
		(13 "F.Paste" user "Package Geometry/Pastemask Top")
		(15 "B.Paste" user "Package Geometry/Pastemask Bottom")
		(5 "F.SilkS" user "Ref Des/Silkscreen Top")
		(7 "B.SilkS" user "Ref Des/Silkscreen Bottom")
		(1 "F.Mask" user "Board Geometry/Soldermask Top")
		(3 "B.Mask" user "Board Geometry/Soldermask Bottom")
		(17 "Dwgs.User" user "User.Drawings")
		(19 "Cmts.User" user "User.Comments")
		(21 "Eco1.User" user "User.Eco1")
		(23 "Eco2.User" user "User.Eco2")
		(25 "Edge.Cuts" user "Board Geometry/Outline")
		(27 "Margin" user)
		(31 "F.CrtYd" user "Package Geometry/Place Bound Top")
		(29 "B.CrtYd" user "Package Geometry/Place Bound Bottom")
		(35 "F.Fab" user "Ref Des/Assembly Top")
		(33 "B.Fab" user "Ref Des/Assembly Bottom")
	)
	(footprint ""
		(layer "F.Cu")
		(at 201.00036 -116.804948 180)
		(property "Reference" "R4157"
			(at 0 0 180)
			(layer "F.SilkS")
			(hide yes)
			(effects
				(font
					(size 1.27 1.27)
				)
			)
		)
		(property "Value" ""
			(at 0 0 180)
			(layer "F.Fab")
			(effects
				(font
					(size 1.27 1.27)
				)
			)
		)
		(duplicate_pad_numbers_are_jumpers no)
		(fp_line
			(start 0.7874 0.4064)
			(end -0.7874 0.4064)
			(stroke
				(width 0.1524)
				(type default)
			)
			(layer "F.SilkS")
		)
		(fp_line
			(start 0.7874 -0.4064)
			(end 0.7874 0.4064)
			(stroke
				(width 0.1524)
				(type default)
			)
			(layer "F.SilkS")
		)
		(fp_line
			(start -0.7874 0.4064)
			(end -0.7874 -0.4064)
			(stroke
				(width 0.1524)
				(type default)
			)
			(layer "F.SilkS")
		)
		(fp_line
			(start -0.7874 -0.4064)
			(end 0.7874 -0.4064)
			(stroke
				(width 0.1524)
				(type default)
			)
			(layer "F.SilkS")
		)
		(fp_line
			(start 0.67945 0.3048)
			(end 0.120396 0.3048)
			(stroke
				(width 0.1)
				(type default)
			)
			(layer "F.Fab")
		)
		(fp_line
			(start 0.67945 -0.3048)
			(end 0.67945 0.3048)
			(stroke
				(width 0.1)
				(type default)
			)
			(layer "F.Fab")
		)
		(fp_line
			(start 0.12065 -0.2794)
			(end 0.12065 -0.3048)
			(stroke
				(width 0.1)
				(type default)
			)
			(layer "F.Fab")
		)
		(fp_line
			(start 0.12065 -0.3048)
			(end 0.67945 -0.3048)
			(stroke
				(width 0.1)
				(type default)
			)
			(layer "F.Fab")
		)
		(fp_line
			(start 0.120396 0.3048)
			(end 0.120396 0.2794)
			(stroke
				(width 0.1)
				(type default)
			)
			(layer "F.Fab")
		)
		(fp_line
			(start 0.120396 0.2794)
			(end -0.12065 0.2794)
			(stroke
				(width 0.1)
				(type default)
			)
			(layer "F.Fab")
		)
		(fp_line
			(start -0.12065 0.3048)
			(end -0.67945 0.3048)
			(stroke
				(width 0.1)
				(type default)
			)
			(layer "F.Fab")
		)
		(fp_line
			(start -0.12065 0.2794)
			(end -0.12065 0.3048)
			(stroke
				(width 0.1)
				(type default)
			)
			(layer "F.Fab")
		)
		(fp_line
			(start -0.12065 -0.2794)
			(end 0.12065 -0.2794)
			(stroke
				(width 0.1)
				(type default)
			)
			(layer "F.Fab")
		)
		(fp_line
			(start -0.12065 -0.305054)
			(end -0.12065 -0.2794)
			(stroke
				(width 0.1)
				(type default)
			)
			(layer "F.Fab")
		)
		(fp_line
			(start -0.67945 0.3048)
			(end -0.67945 -0.305054)
			(stroke
				(width 0.1)
				(type default)
			)
			(layer "F.Fab")
		)
		(fp_line
			(start -0.67945 -0.305054)
			(end -0.12065 -0.305054)
			(stroke
				(width 0.1)
				(type default)
			)
			(layer "F.Fab")
		)
		(pad "1" smd circle
			(at -0.40005 0 180)
			(size 0 0)
			(layers "F.Cu" "F.Mask" "F.Paste")
			(net "PRSNT_CABLE_GPU_A1_ISO_N")
		)
		(pad "2" smd circle
			(at 0.40005 0 180)
			(size 0 0)
			(layers "F.Cu" "F.Mask" "F.Paste")
			(net "PRSNT_CABLE_GPU_A1_ISO_R_N")
		)
	)
	(footprint ""
		(layer "F.Cu")
		(at 504.058428 -303.58588 90)
		(property "Reference" "X3"
			(at -2.637536 3.163062 90)
			(unlocked yes)
			(layer "F.SilkS")
			(effects
				(font
					(size 0.7874 0.5842)
					(thickness 0.1524)
				)
				(justify left)
			)
		)
		(property "Value" ""
			(at 0 0 90)
			(layer "F.Fab")
			(effects
				(font
					(size 1.27 1.27)
				)
			)
		)
		(property "Device Type" "TP_TDR_4P_FTS_MPKT4_H025P0200_I"
			(at 1.30175 1.27 180)
			(unlocked yes)
			(layer "F.Fab")
			(hide yes)
			(effects
				(font
					(size 0.635 0.4064)
					(thickness 0.1524)
				)
			)
		)
		(property "User Part Number" "TP15"
			(at 1.30175 1.27 180)
			(unlocked yes)
			(layer "Cmts.User")
			(hide yes)
			(effects
				(font
					(size 0.635 0.4064)
					(thickness 0.1524)
				)
			)
		)
		(duplicate_pad_numbers_are_jumpers no)
		(fp_line
			(start 2.54 -1.27)
			(end 0 -1.27)
			(stroke
				(width 0.1524)
				(type default)
			)
			(layer "F.SilkS")
		)
		(fp_line
			(start 0 -1.27)
			(end 0 -0.635)
			(stroke
				(width 0.1524)
				(type default)
			)
			(layer "F.SilkS")
		)
		(fp_line
			(start 2.54 -1.1303)
			(end 2.54 -1.27)
			(stroke
				(width 0.1524)
				(type default)
			)
			(layer "F.SilkS")
		)
		(fp_line
			(start 0 0.635)
			(end 0 1.905)
			(stroke
				(width 0.1524)
				(type default)
			)
			(layer "F.SilkS")
		)
		(fp_line
			(start 2.54 1.4097)
			(end 2.54 1.1303)
			(stroke
				(width 0.1524)
				(type default)
			)
			(layer "F.SilkS")
		)
		(fp_line
			(start 0 3.175)
			(end 0 3.81)
			(stroke
				(width 0.1524)
				(type default)
			)
			(layer "F.SilkS")
		)
		(fp_line
			(start 2.54 3.81)
			(end 2.54 3.6703)
			(stroke
				(width 0.1524)
				(type default)
			)
			(layer "F.SilkS")
		)
		(fp_line
			(start 0 3.81)
			(end 2.54 3.81)
			(stroke
				(width 0.1524)
				(type default)
			)
			(layer "F.SilkS")
		)
		(fp_poly
			(pts
				(xy -0.761746 0) (xy -2.285746 0.762) (xy -2.285746 -0.762)
			)
			(stroke
				(width 0)
				(type default)
			)
			(fill yes)
			(layer "F.SilkS")
		)
		(fp_line
			(start 2.54 -1.27)
			(end 0 -1.27)
			(stroke
				(width 0.1)
				(type default)
			)
			(layer "F.Fab")
		)
		(fp_line
			(start 0 -1.27)
			(end 0 3.81)
			(stroke
				(width 0.1)
				(type default)
			)
			(layer "F.Fab")
		)
		(fp_line
			(start 2.54 3.81)
			(end 2.54 -1.27)
			(stroke
				(width 0.1)
				(type default)
			)
			(layer "F.Fab")
		)
		(fp_line
			(start 0 3.81)
			(end 2.54 3.81)
			(stroke
				(width 0.1)
				(type default)
			)
			(layer "F.Fab")
		)
		(fp_poly
			(pts
				(xy -0.761746 0) (xy -2.285746 -0.762) (xy -2.285746 0.762)
			)
			(stroke
				(width 0)
				(type default)
			)
			(fill yes)
			(layer "F.Fab")
		)
		(pad "1" thru_hole circle
			(at 0 0 90)
			(size 1.0033 1.0033)
			(drill 0.249936)
			(layers "*.Cu" "*.Mask")
			(remove_unused_layers no)
			(net "TDR_DIFF_85_IN2_DP")
			(clearance 0.10795)
			(thermal_gap 0.10795)
			(padstack
				(mode front_inner_back)
				(layer "Inner"
					(shape circle)
					(size 0.8001 0.8001)
					(clearance 0.1524)
				)
				(layer "B.Cu"
					(shape circle)
					(size 1.0033 1.0033)
					(clearance 0.10795)
				)
			)
		)
		(pad "2" thru_hole circle
			(at 2.54 0 90)
			(size 1.9939 1.9939)
			(drill 0.249936)
			(layers "*.Cu" "*.Mask")
			(remove_unused_layers no)
			(net "T1_GND")
			(clearance 0.10795)
			(thermal_gap 0.10795)
			(padstack
				(mode front_inner_back)
				(layer "Inner"
					(shape circle)
					(size 0.8001 0.8001)
					(clearance 0.1524)
				)
				(layer "B.Cu"
					(shape circle)
					(size 1.9939 1.9939)
					(clearance 0.10795)
				)
			)
		)
		(pad "3" thru_hole circle
			(at 2.54 2.54 90)
			(size 1.9939 1.9939)
			(drill 0.249936)
			(layers "*.Cu" "*.Mask")
			(remove_unused_layers no)
			(net "T1_GND")
			(clearance 0.10795)
			(thermal_gap 0.10795)
			(padstack
				(mode front_inner_back)
				(layer "Inner"
					(shape circle)
					(size 0.8001 0.8001)
					(clearance 0.1524)
				)
				(layer "B.Cu"
					(shape circle)
					(size 1.9939 1.9939)
					(clearance 0.10795)
				)
			)
		)
		(pad "4" thru_hole circle
			(at 0 2.54 90)
			(size 1.0033 1.0033)
			(drill 0.249936)
			(layers "*.Cu" "*.Mask")
			(remove_unused_layers no)
			(net "TDR_DIFF_85_IN2_DN")
			(clearance 0.10795)
			(thermal_gap 0.10795)
			(padstack
				(mode front_inner_back)
				(layer "Inner"
					(shape circle)
					(size 0.8001 0.8001)
					(clearance 0.1524)
				)
				(layer "B.Cu"
					(shape circle)
					(size 1.0033 1.0033)
					(clearance 0.10795)
				)
			)
		)
	)
)
